# T6G (Grand Teton) — schematic netlist excerpt (pin names and nets, part order shuffled) for the footprints in the layout excerpt that follows; sources: Cadence DE-HDL packaged netlist, KiCad conversion of 04192023_DAF0TMB3IC0_F0TG_MB_C_brd_V02_OCP.brd

X9025  TP_TDR_4P_FTS  TP_TDR_4P_DIP EMPTY  pkg TH  page 261
  S1  = TDR_DIFF_85_NECK_IN5_DP
  P1  = T1_GND
  P2  = T1_GND
  S2  = TDR_DIFF_85_NECK_IN5_DN

PR440  Q_RES  0 5% CHIP  pkg 0402LF  page 193 : A = NC_PVDDCR_CPU0_P0_IMON8 ; B = GND

(kicad_pcb
	(version 20260206)
	(generator "pcbnew")
	(generator_version "10.0")
	(general
		(thickness 1.6)
		(legacy_teardrops no)
	)
	(paper "A4")
	(title_block
		(title "04192023_DAF0TMB3IC0_F0TG_MB_C_brd_V02_OCP.brd")
		(comment 1 "Grand Teton / footprints 6287-6288 of 8354")
	)
	(layers
		(0 "F.Cu" signal "TOP")
		(4 "In1.Cu" signal "GND")
		(6 "In2.Cu" signal "IN1")
		(8 "In3.Cu" signal "GND1")
		(10 "In4.Cu" signal "IN2")
		(12 "In5.Cu" signal "GND2")
		(14 "In6.Cu" signal "IN3")
		(16 "In7.Cu" signal "GND3")
		(18 "In8.Cu" signal "VCC")
		(20 "In9.Cu" signal "VCC1")
		(22 "In10.Cu" signal "GND4")
		(24 "In11.Cu" signal "IN4")
		(26 "In12.Cu" signal "GND5")
		(28 "In13.Cu" signal "IN5")
		(30 "In14.Cu" signal "GND6")
		(32 "In15.Cu" signal "IN6")
		(34 "In16.Cu" signal "GND7")
		(2 "B.Cu" signal "BOTTOM")
		(9 "F.Adhes" user "F.Adhesive")
		(11 "B.Adhes" user "B.Adhesive")
		(13 "F.Paste" user "Package Geometry/Pastemask Top")
		(15 "B.Paste" user "Package Geometry/Pastemask Bottom")
		(5 "F.SilkS" user "Ref Des/Silkscreen Top")
		(7 "B.SilkS" user "Ref Des/Silkscreen Bottom")
		(1 "F.Mask" user "Board Geometry/Soldermask Top")
		(3 "B.Mask" user "Board Geometry/Soldermask Bottom")
		(17 "Dwgs.User" user "User.Drawings")
		(19 "Cmts.User" user "User.Comments")
		(21 "Eco1.User" user "User.Eco1")
		(23 "Eco2.User" user "User.Eco2")
		(25 "Edge.Cuts" user "Board Geometry/Outline")
		(27 "Margin" user)
		(31 "F.CrtYd" user "Package Geometry/Place Bound Top")
		(29 "B.CrtYd" user "Package Geometry/Place Bound Bottom")
		(35 "F.Fab" user "Ref Des/Assembly Top")
		(33 "B.Fab" user "Ref Des/Assembly Bottom")
	)
	(footprint ""
		(layer "B.Cu")
		(at 380.629922 -148.30171 -90)
		(property "Reference" "PR440"
			(at 0 0 90)
			(layer "B.SilkS")
			(hide yes)
			(effects
				(font
					(size 1.27 1.27)
				)
				(justify mirror)
			)
		)
		(property "Value" ""
			(at 0 0 90)
			(layer "B.Fab")
			(effects
				(font
					(size 1.27 1.27)
				)
				(justify mirror)
			)
		)
		(duplicate_pad_numbers_are_jumpers no)
		(fp_line
			(start -0.7874 0.4064)
			(end 0.7874 0.4064)
			(stroke
				(width 0.1524)
				(type default)
			)
			(layer "B.SilkS")
		)
		(fp_line
			(start 0.7874 0.4064)
			(end 0.7874 -0.4064)
			(stroke
				(width 0.1524)
				(type default)
			)
			(layer "B.SilkS")
		)
		(fp_line
			(start -0.7874 -0.4064)
			(end -0.7874 0.4064)
			(stroke
				(width 0.1524)
				(type default)
			)
			(layer "B.SilkS")
		)
		(fp_line
			(start 0.7874 -0.4064)
			(end -0.7874 -0.4064)
			(stroke
				(width 0.1524)
				(type default)
			)
			(layer "B.SilkS")
		)
		(fp_line
			(start -0.67945 0.3048)
			(end -0.120396 0.3048)
			(stroke
				(width 0.1)
				(type default)
			)
			(layer "B.Fab")
		)
		(fp_line
			(start -0.120396 0.3048)
			(end -0.120396 0.2794)
			(stroke
				(width 0.1)
				(type default)
			)
			(layer "B.Fab")
		)
		(fp_line
			(start 0.12065 0.3048)
			(end 0.67945 0.3048)
			(stroke
				(width 0.1)
				(type default)
			)
			(layer "B.Fab")
		)
		(fp_line
			(start 0.67945 0.3048)
			(end 0.67945 -0.305054)
			(stroke
				(width 0.1)
				(type default)
			)
			(layer "B.Fab")
		)
		(fp_line
			(start -0.120396 0.2794)
			(end 0.12065 0.2794)
			(stroke
				(width 0.1)
				(type default)
			)
			(layer "B.Fab")
		)
		(fp_line
			(start 0.12065 0.2794)
			(end 0.12065 0.3048)
			(stroke
				(width 0.1)
				(type default)
			)
			(layer "B.Fab")
		)
		(fp_line
			(start -0.12065 -0.2794)
			(end -0.12065 -0.3048)
			(stroke
				(width 0.1)
				(type default)
			)
			(layer "B.Fab")
		)
		(fp_line
			(start 0.12065 -0.2794)
			(end -0.12065 -0.2794)
			(stroke
				(width 0.1)
				(type default)
			)
			(layer "B.Fab")
		)
		(fp_line
			(start -0.67945 -0.3048)
			(end -0.67945 0.3048)
			(stroke
				(width 0.1)
				(type default)
			)
			(layer "B.Fab")
		)
		(fp_line
			(start -0.12065 -0.3048)
			(end -0.67945 -0.3048)
			(stroke
				(width 0.1)
				(type default)
			)
			(layer "B.Fab")
		)
		(fp_line
			(start 0.12065 -0.305054)
			(end 0.12065 -0.2794)
			(stroke
				(width 0.1)
				(type default)
			)
			(layer "B.Fab")
		)
		(fp_line
			(start 0.67945 -0.305054)
			(end 0.12065 -0.305054)
			(stroke
				(width 0.1)
				(type default)
			)
			(layer "B.Fab")
		)
		(pad "1" smd circle
			(at 0.40005 0 90)
			(size 0 0)
			(layers "B.Cu" "B.Mask" "B.Paste")
			(net "NC_PVDDCR_CPU0_P0_IMON8")
		)
		(pad "2" smd circle
			(at -0.40005 0 90)
			(size 0 0)
			(layers "B.Cu" "B.Mask" "B.Paste")
			(net "GND")
		)
	)
	(footprint ""
		(layer "B.Cu")
		(at 498.311424 -306.87518 90)
		(property "Reference" "X9025"
			(at 4.62026 -1.55829 90)
			(unlocked yes)
			(layer "B.SilkS")
			(effects
				(font
					(size 0.7874 0.5842)
					(thickness 0.1524)
				)
				(justify left mirror)
			)
		)
		(property "Value" ""
			(at 0 0 90)
			(layer "B.Fab")
			(effects
				(font
					(size 1.27 1.27)
				)
				(justify mirror)
			)
		)
		(property "User Part Number" "N_A"
			(at -1.30175 1.27 0)
			(unlocked yes)
			(layer "Cmts.User")
			(hide yes)
			(effects
				(font
					(size 0.635 0.4064)
					(thickness 0.1524)
				)
				(justify mirror)
			)
		)
		(property "Device Type" "TP_TDR_4P_FTS_TH-TP_TDR_4P_DIP,EMPTY,TP15"
			(at -1.30175 1.27 0)
			(unlocked yes)
			(layer "B.Fab")
			(hide yes)
			(effects
				(font
					(size 0.635 0.4064)
					(thickness 0.1524)
				)
				(justify mirror)
			)
		)
		(duplicate_pad_numbers_are_jumpers no)
		(fp_line
			(start 0 -1.27)
			(end 0 -0.635)
			(stroke
				(width 0.1524)
				(type default)
			)
			(layer "B.SilkS")
		)
		(fp_line
			(start -2.54 -1.27)
			(end 0 -1.27)
			(stroke
				(width 0.1524)
				(type default)
			)
			(layer "B.SilkS")
		)
		(fp_line
			(start -2.54 -1.1303)
			(end -2.54 -1.27)
			(stroke
				(width 0.1524)
				(type default)
			)
			(layer "B.SilkS")
		)
		(fp_line
			(start 0 0.635)
			(end 0 1.905)
			(stroke
				(width 0.1524)
				(type default)
			)
			(layer "B.SilkS")
		)
		(fp_line
			(start -2.54 1.4097)
			(end -2.54 1.1303)
			(stroke
				(width 0.1524)
				(type default)
			)
			(layer "B.SilkS")
		)
		(fp_line
			(start 0 3.175)
			(end 0 3.81)
			(stroke
				(width 0.1524)
				(type default)
			)
			(layer "B.SilkS")
		)
		(fp_line
			(start 0 3.81)
			(end -2.54 3.81)
			(stroke
				(width 0.1524)
				(type default)
			)
			(layer "B.SilkS")
		)
		(fp_line
			(start -2.54 3.81)
			(end -2.54 3.6703)
			(stroke
				(width 0.1524)
				(type default)
			)
			(layer "B.SilkS")
		)
		(fp_poly
			(pts
				(xy 0.761746 0) (xy 2.285746 -0.762) (xy 2.285746 0.762)
			)
			(stroke
				(width 0)
				(type default)
			)
			(fill yes)
			(layer "B.SilkS")
		)
		(fp_line
			(start 0 -1.27)
			(end 0 3.81)
			(stroke
				(width 0.1)
				(type default)
			)
			(layer "B.Fab")
		)
		(fp_line
			(start -2.54 -1.27)
			(end 0 -1.27)
			(stroke
				(width 0.1)
				(type default)
			)
			(layer "B.Fab")
		)
		(fp_line
			(start 0 3.81)
			(end -2.54 3.81)
			(stroke
				(width 0.1)
				(type default)
			)
			(layer "B.Fab")
		)
		(fp_line
			(start -2.54 3.81)
			(end -2.54 -1.27)
			(stroke
				(width 0.1)
				(type default)
			)
			(layer "B.Fab")
		)
		(fp_poly
			(pts
				(xy 0.761746 0) (xy 2.285746 -0.762) (xy 2.285746 0.762)
			)
			(stroke
				(width 0)
				(type default)
			)
			(fill yes)
			(layer "B.Fab")
		)
		(pad "1" thru_hole circle
			(at 0 0 270)
			(size 1.0033 1.0033)
			(drill 0.249936)
			(layers "*.Cu" "*.Mask")
			(remove_unused_layers no)
			(net "TDR_DIFF_85_NECK_IN5_DP")
			(clearance 0.10795)
			(padstack
				(mode front_inner_back)
				(layer "Inner"
					(shape circle)
					(size 0.8001 0.8001)
					(clearance 0.1524)
				)
				(layer "B.Cu"
					(shape circle)
					(size 1.0033 1.0033)
					(thermal_gap 0.10795)
					(clearance 0.10795)
				)
			)
		)
		(pad "2" thru_hole circle
			(at -2.54 0 270)
			(size 1.9939 1.9939)
			(drill 0.249936)
			(layers "*.Cu" "*.Mask")
			(remove_unused_layers no)
			(net "T1_GND")
			(clearance 0.10795)
			(padstack
				(mode front_inner_back)
				(layer "Inner"
					(shape circle)
					(size 0.8001 0.8001)
					(clearance 0.1524)
				)
				(layer "B.Cu"
					(shape circle)
					(size 1.9939 1.9939)
					(thermal_gap 0.10795)
					(clearance 0.10795)
				)
			)
		)
		(pad "3" thru_hole circle
			(at -2.54 2.54 270)
			(size 1.9939 1.9939)
			(drill 0.249936)
			(layers "*.Cu" "*.Mask")
			(remove_unused_layers no)
			(net "T1_GND")
			(clearance 0.10795)
			(padstack
				(mode front_inner_back)
				(layer "Inner"
					(shape circle)
					(size 0.8001 0.8001)
					(clearance 0.1524)
				)
				(layer "B.Cu"
					(shape circle)
					(size 1.9939 1.9939)
					(thermal_gap 0.10795)
					(clearance 0.10795)
				)
			)
		)
		(pad "4" thru_hole circle
			(at 0 2.54 270)
			(size 1.0033 1.0033)
			(drill 0.249936)
			(layers "*.Cu" "*.Mask")
			(remove_unused_layers no)
			(net "TDR_DIFF_85_NECK_IN5_DN")
			(clearance 0.10795)
			(padstack
				(mode front_inner_back)
				(layer "Inner"
					(shape circle)
					(size 0.8001 0.8001)
					(clearance 0.1524)
				)
				(layer "B.Cu"
					(shape circle)
					(size 1.0033 1.0033)
					(thermal_gap 0.10795)
					(clearance 0.10795)
				)
			)
		)
	)
)
